(kicad_pcb
	(version 20260206)
	(generator "pcbnew")
	(generator_version "10.0")
	(general
		(thickness 1.6)
		(legacy_teardrops no)
	)
	(paper "A4")
	(title_block
		(title "baseboard — 13948-1b.1110WZS1818.brd")
		(comment 1 "Honey Badger (Wiwynn) / footprints 728-728 of 2523")
	)
	(layers
		(0 "F.Cu" signal "TOP")
		(4 "In1.Cu" signal "L2GND")
		(6 "In2.Cu" signal "L3")
		(8 "In3.Cu" signal "L4VCC")
		(10 "In4.Cu" signal "L5VCC")
		(12 "In5.Cu" signal "L6")
		(14 "In6.Cu" signal "L7GND")
		(2 "B.Cu" signal "BOTTOM")
		(9 "F.Adhes" user "F.Adhesive")
		(11 "B.Adhes" user "B.Adhesive")
		(13 "F.Paste" user "Package Geometry/Pastemask Top")
		(15 "B.Paste" user "Package Geometry/Pastemask Bottom")
		(5 "F.SilkS" user "Ref Des/Silkscreen Top")
		(7 "B.SilkS" user "Ref Des/Silkscreen Bottom")
		(1 "F.Mask" user "Board Geometry/Soldermask Top")
		(3 "B.Mask" user "Board Geometry/Soldermask Bottom")
		(17 "Dwgs.User" user "User.Drawings")
		(19 "Cmts.User" user "User.Comments")
		(21 "Eco1.User" user "User.Eco1")
		(23 "Eco2.User" user "User.Eco2")
		(25 "Edge.Cuts" user "Board Geometry/Outline")
		(27 "Margin" user)
		(31 "F.CrtYd" user "Package Geometry/Place Bound Top")
		(29 "B.CrtYd" user "Package Geometry/Place Bound Bottom")
		(35 "F.Fab" user "Ref Des/Assembly Top")
		(33 "B.Fab" user "Ref Des/Assembly Bottom")
	)
	(footprint ""
		(layer "F.Cu")
		(at 290.898072 -199.335136 -90)
		(property "Reference" "U18"
			(at 0 0 270)
			(layer "F.SilkS")
			(hide yes)
			(effects
				(font
					(size 1.27 1.27)
				)
			)
		)
		(property "Value" "NT5CB64M16FP-DH-GP"
			(at -8.221218 -0.6731 270)
			(unlocked yes)
			(layer "F.Fab")
			(hide yes)
			(effects
				(font
					(size 1.016 1.016)
					(thickness 0.1524)
				)
			)
		)
		(property "Device Type" "BGA96D0913H48"
			(at -8.221218 -2.1971 270)
			(unlocked yes)
			(layer "F.Fab")
			(hide yes)
			(effects
				(font
					(size 1.016 1.016)
					(thickness 0.1524)
				)
			)
		)
		(duplicate_pad_numbers_are_jumpers no)
		(fp_line
			(start -4.500118 6.500114)
			(end 4.500118 6.500114)
			(stroke
				(width 0.1524)
				(type default)
			)
			(layer "F.SilkS")
		)
		(fp_line
			(start 4.500118 6.500114)
			(end 4.500118 -6.500114)
			(stroke
				(width 0.1524)
				(type default)
			)
			(layer "F.SilkS")
		)
		(fp_line
			(start -4.830318 -5.230114)
			(end -4.830318 -6.830314)
			(stroke
				(width 0.508)
				(type default)
			)
			(layer "F.SilkS")
		)
		(fp_line
			(start -4.500118 -6.500114)
			(end -4.500118 6.500114)
			(stroke
				(width 0.1524)
				(type default)
			)
			(layer "F.SilkS")
		)
		(fp_line
			(start 4.500118 -6.500114)
			(end -4.500118 -6.500114)
			(stroke
				(width 0.1524)
				(type default)
			)
			(layer "F.SilkS")
		)
		(fp_line
			(start -4.830318 -6.830314)
			(end -3.230118 -6.830314)
			(stroke
				(width 0.508)
				(type default)
			)
			(layer "F.SilkS")
		)
		(fp_rect
			(start -4.500118 6.500114)
			(end 4.500118 -6.500114)
			(stroke
				(width 0)
				(type default)
			)
			(fill no)
			(layer "F.CrtYd")
		)
		(fp_poly
			(pts
				(xy -5.500116 7.500112) (xy -5.500116 -7.500112) (xy 5.500116 -7.500112) (xy 5.500116 -0.0254) (xy 4.500118 -0.0254)
				(xy 4.500118 -6.500114) (xy -4.500118 -6.500114) (xy -4.500118 6.500114) (xy 4.500118 6.500114)
				(xy 4.500118 -0.0127) (xy 5.500116 -0.0127) (xy 5.500116 7.500112)
			)
			(stroke
				(width 0)
				(type default)
			)
			(fill no)
			(layer "F.CrtYd")
		)
		(fp_rect
			(start -6.500114 8.50011)
			(end 6.500114 -8.50011)
			(stroke
				(width 0)
				(type default)
			)
			(fill no)
			(layer "F.Fab")
		)
		(pad "A1" smd circle
			(at -3.199892 -5.999988 270)
			(size 0.3556 0.3556)
			(layers "F.Cu" "F.Mask" "F.Paste")
			(net "P1V53_STBY")
		)
		(pad "A2" smd circle
			(at -2.400046 -5.999988 270)
			(size 0.3556 0.3556)
			(layers "F.Cu" "F.Mask" "F.Paste")
			(net "MEMDQ_15")
		)
		(pad "A3" smd circle
			(at -1.599946 -5.999988 270)
			(size 0.3556 0.3556)
			(layers "F.Cu" "F.Mask" "F.Paste")
			(net "MEMDQ_14")
		)
		(pad "A7" smd circle
			(at 1.599946 -5.999988 270)
			(size 0.3556 0.3556)
			(layers "F.Cu" "F.Mask" "F.Paste")
			(net "MEMDQ_10")
		)
		(pad "A8" smd circle
			(at 2.400046 -5.999988 270)
			(size 0.3556 0.3556)
			(layers "F.Cu" "F.Mask" "F.Paste")
			(net "P1V53_STBY")
		)
		(pad "A9" smd circle
			(at 3.199892 -5.999988 270)
			(size 0.3556 0.3556)
			(layers "F.Cu" "F.Mask" "F.Paste")
			(net "GND")
		)
		(pad "B1" smd circle
			(at -3.199892 -5.199888 270)
			(size 0.3556 0.3556)
			(layers "F.Cu" "F.Mask" "F.Paste")
			(net "GND")
		)
		(pad "B2" smd circle
			(at -2.400046 -5.199888 270)
			(size 0.3556 0.3556)
			(layers "F.Cu" "F.Mask" "F.Paste")
			(net "P1V53_STBY")
		)
		(pad "B3" smd circle
			(at -1.599946 -5.199888 270)
			(size 0.3556 0.3556)
			(layers "F.Cu" "F.Mask" "F.Paste")
			(net "GND")
		)
		(pad "B7" smd circle
			(at 1.599946 -5.199888 270)
			(size 0.3556 0.3556)
			(layers "F.Cu" "F.Mask" "F.Paste")
			(net "MEMDQS_N1")
		)
		(pad "B8" smd circle
			(at 2.400046 -5.199888 270)
			(size 0.3556 0.3556)
			(layers "F.Cu" "F.Mask" "F.Paste")
			(net "MEMDQ_9")
		)
		(pad "B9" smd circle
			(at 3.199892 -5.199888 270)
			(size 0.3556 0.3556)
			(layers "F.Cu" "F.Mask" "F.Paste")
			(net "GND")
		)
		(pad "C1" smd circle
			(at -3.199892 -4.400042 270)
			(size 0.3556 0.3556)
			(layers "F.Cu" "F.Mask" "F.Paste")
			(net "P1V53_STBY")
		)
		(pad "C2" smd circle
			(at -2.400046 -4.400042 270)
			(size 0.3556 0.3556)
			(layers "F.Cu" "F.Mask" "F.Paste")
			(net "MEMDQ_12")
		)
		(pad "C3" smd circle
			(at -1.599946 -4.400042 270)
			(size 0.3556 0.3556)
			(layers "F.Cu" "F.Mask" "F.Paste")
			(net "MEMDQ_11")
		)
		(pad "C7" smd circle
			(at 1.599946 -4.400042 270)
			(size 0.3556 0.3556)
			(layers "F.Cu" "F.Mask" "F.Paste")
			(net "MEMDQS_P1")
		)
		(pad "C8" smd circle
			(at 2.400046 -4.400042 270)
			(size 0.3556 0.3556)
			(layers "F.Cu" "F.Mask" "F.Paste")
			(net "MEMDQ_13")
		)
		(pad "C9" smd circle
			(at 3.199892 -4.400042 270)
			(size 0.3556 0.3556)
			(layers "F.Cu" "F.Mask" "F.Paste")
			(net "P1V53_STBY")
		)
		(pad "D1" smd circle
			(at -3.199892 -3.599942 270)
			(size 0.3556 0.3556)
			(layers "F.Cu" "F.Mask" "F.Paste")
			(net "GND")
		)
		(pad "D2" smd circle
			(at -2.400046 -3.599942 270)
			(size 0.3556 0.3556)
			(layers "F.Cu" "F.Mask" "F.Paste")
			(net "P1V53_STBY")
		)
		(pad "D3" smd circle
			(at -1.599946 -3.599942 270)
			(size 0.3556 0.3556)
			(layers "F.Cu" "F.Mask" "F.Paste")
			(net "MEMDM_1")
		)
		(pad "D7" smd circle
			(at 1.599946 -3.599942 270)
			(size 0.3556 0.3556)
			(layers "F.Cu" "F.Mask" "F.Paste")
			(net "MEMDQ_8")
		)
		(pad "D8" smd circle
			(at 2.400046 -3.599942 270)
			(size 0.3556 0.3556)
			(layers "F.Cu" "F.Mask" "F.Paste")
			(net "GND")
		)
		(pad "D9" smd circle
			(at 3.199892 -3.599942 270)
			(size 0.3556 0.3556)
			(layers "F.Cu" "F.Mask" "F.Paste")
			(net "P1V53_STBY")
		)
		(pad "E1" smd circle
			(at -3.199892 -2.800096 270)
			(size 0.3556 0.3556)
			(layers "F.Cu" "F.Mask" "F.Paste")
			(net "GND")
		)
		(pad "E2" smd circle
			(at -2.400046 -2.800096 270)
			(size 0.3556 0.3556)
			(layers "F.Cu" "F.Mask" "F.Paste")
			(net "GND")
		)
		(pad "E3" smd circle
			(at -1.599946 -2.800096 270)
			(size 0.3556 0.3556)
			(layers "F.Cu" "F.Mask" "F.Paste")
			(net "MEMDQ_7")
		)
		(pad "E7" smd circle
			(at 1.599946 -2.800096 270)
			(size 0.3556 0.3556)
			(layers "F.Cu" "F.Mask" "F.Paste")
			(net "MEMDM_0")
		)
		(pad "E8" smd circle
			(at 2.400046 -2.800096 270)
			(size 0.3556 0.3556)
			(layers "F.Cu" "F.Mask" "F.Paste")
			(net "GND")
		)
		(pad "E9" smd circle
			(at 3.199892 -2.800096 270)
			(size 0.3556 0.3556)
			(layers "F.Cu" "F.Mask" "F.Paste")
			(net "P1V53_STBY")
		)
		(pad "F1" smd circle
			(at -3.199892 -1.999996 270)
			(size 0.3556 0.3556)
			(layers "F.Cu" "F.Mask" "F.Paste")
			(net "P1V53_STBY")
		)
		(pad "F2" smd circle
			(at -2.400046 -1.999996 270)
			(size 0.3556 0.3556)
			(layers "F.Cu" "F.Mask" "F.Paste")
			(net "MEMDQ_4")
		)
		(pad "F3" smd circle
			(at -1.599946 -1.999996 270)
			(size 0.3556 0.3556)
			(layers "F.Cu" "F.Mask" "F.Paste")
			(net "MEMDQS_P0")
		)
		(pad "F7" smd circle
			(at 1.599946 -1.999996 270)
			(size 0.3556 0.3556)
			(layers "F.Cu" "F.Mask" "F.Paste")
			(net "MEMDQ_3")
		)
		(pad "F8" smd circle
			(at 2.400046 -1.999996 270)
			(size 0.3556 0.3556)
			(layers "F.Cu" "F.Mask" "F.Paste")
			(net "MEMDQ_2")
		)
		(pad "F9" smd circle
			(at 3.199892 -1.999996 270)
			(size 0.3556 0.3556)
			(layers "F.Cu" "F.Mask" "F.Paste")
			(net "GND")
		)
		(pad "G1" smd circle
			(at -3.199892 -1.199896 270)
			(size 0.3556 0.3556)
			(layers "F.Cu" "F.Mask" "F.Paste")
			(net "GND")
		)
		(pad "G2" smd circle
			(at -2.400046 -1.199896 270)
			(size 0.3556 0.3556)
			(layers "F.Cu" "F.Mask" "F.Paste")
			(net "MEMDQ_5")
		)
		(pad "G3" smd circle
			(at -1.599946 -1.199896 270)
			(size 0.3556 0.3556)
			(layers "F.Cu" "F.Mask" "F.Paste")
			(net "MEMDQS_N0")
		)
		(pad "G7" smd circle
			(at 1.599946 -1.199896 270)
			(size 0.3556 0.3556)
			(layers "F.Cu" "F.Mask" "F.Paste")
			(net "P1V53_STBY")
		)
		(pad "G8" smd circle
			(at 2.400046 -1.199896 270)
			(size 0.3556 0.3556)
			(layers "F.Cu" "F.Mask" "F.Paste")
			(net "GND")
		)
		(pad "G9" smd circle
			(at 3.199892 -1.199896 270)
			(size 0.3556 0.3556)
			(layers "F.Cu" "F.Mask" "F.Paste")
			(net "GND")
		)
		(pad "H1" smd circle
			(at -3.199892 -0.40005 270)
			(size 0.3556 0.3556)
			(layers "F.Cu" "F.Mask" "F.Paste")
			(net "DDR_VREF")
		)
		(pad "H2" smd circle
			(at -2.400046 -0.40005 270)
			(size 0.3556 0.3556)
			(layers "F.Cu" "F.Mask" "F.Paste")
			(net "P1V53_STBY")
		)
		(pad "H3" smd circle
			(at -1.599946 -0.40005 270)
			(size 0.3556 0.3556)
			(layers "F.Cu" "F.Mask" "F.Paste")
			(net "MEMDQ_1")
		)
		(pad "H7" smd circle
			(at 1.599946 -0.40005 270)
			(size 0.3556 0.3556)
			(layers "F.Cu" "F.Mask" "F.Paste")
			(net "MEMDQ_0")
		)
		(pad "H8" smd circle
			(at 2.400046 -0.40005 270)
			(size 0.3556 0.3556)
			(layers "F.Cu" "F.Mask" "F.Paste")
			(net "MEMDQ_6")
		)
		(pad "H9" smd circle
			(at 3.199892 -0.40005 270)
			(size 0.3556 0.3556)
			(layers "F.Cu" "F.Mask" "F.Paste")
			(net "P1V53_STBY")
		)
		(pad "J1" smd circle
			(at -3.199892 0.40005 270)
			(size 0.3556 0.3556)
			(layers "F.Cu" "F.Mask" "F.Paste")
			(net "Net_6")
		)
		(pad "J2" smd circle
			(at -2.400046 0.40005 270)
			(size 0.3556 0.3556)
			(layers "F.Cu" "F.Mask" "F.Paste")
			(net "GND")
		)
		(pad "J3" smd circle
			(at -1.599946 0.40005 270)
			(size 0.3556 0.3556)
			(layers "F.Cu" "F.Mask" "F.Paste")
			(net "MEMRASN")
		)
		(pad "J7" smd circle
			(at 1.599946 0.40005 270)
			(size 0.3556 0.3556)
			(layers "F.Cu" "F.Mask" "F.Paste")
			(net "MEMCK_P")
		)
		(pad "J8" smd circle
			(at 2.400046 0.40005 270)
			(size 0.3556 0.3556)
			(layers "F.Cu" "F.Mask" "F.Paste")
			(net "GND")
		)
		(pad "J9" smd circle
			(at 3.199892 0.40005 270)
			(size 0.3556 0.3556)
			(layers "F.Cu" "F.Mask" "F.Paste")
			(net "Net_5")
		)
		(pad "K1" smd circle
			(at -3.199892 1.199896 270)
			(size 0.3556 0.3556)
			(layers "F.Cu" "F.Mask" "F.Paste")
			(net "MEMODT")
		)
		(pad "K2" smd circle
			(at -2.400046 1.199896 270)
			(size 0.3556 0.3556)
			(layers "F.Cu" "F.Mask" "F.Paste")
			(net "P1V53_STBY")
		)
		(pad "K3" smd circle
			(at -1.599946 1.199896 270)
			(size 0.3556 0.3556)
			(layers "F.Cu" "F.Mask" "F.Paste")
			(net "MEMCASN")
		)
		(pad "K7" smd circle
			(at 1.599946 1.199896 270)
			(size 0.3556 0.3556)
			(layers "F.Cu" "F.Mask" "F.Paste")
			(net "MEMCK_N")
		)
		(pad "K8" smd circle
			(at 2.400046 1.199896 270)
			(size 0.3556 0.3556)
			(layers "F.Cu" "F.Mask" "F.Paste")
			(net "P1V53_STBY")
		)
		(pad "K9" smd circle
			(at 3.199892 1.199896 270)
			(size 0.3556 0.3556)
			(layers "F.Cu" "F.Mask" "F.Paste")
			(net "MEMCKE")
		)
		(pad "L1" smd circle
			(at -3.199892 1.999996 270)
			(size 0.3556 0.3556)
			(layers "F.Cu" "F.Mask" "F.Paste")
			(net "Net_4")
		)
		(pad "L2" smd circle
			(at -2.400046 1.999996 270)
			(size 0.3556 0.3556)
			(layers "F.Cu" "F.Mask" "F.Paste")
			(net "MEMCSN")
		)
		(pad "L3" smd circle
			(at -1.599946 1.999996 270)
			(size 0.3556 0.3556)
			(layers "F.Cu" "F.Mask" "F.Paste")
			(net "MEMWEN")
		)
		(pad "L7" smd circle
			(at 1.599946 1.999996 270)
			(size 0.3556 0.3556)
			(layers "F.Cu" "F.Mask" "F.Paste")
			(net "MEMA_10")
		)
		(pad "L8" smd circle
			(at 2.400046 1.999996 270)
			(size 0.3556 0.3556)
			(layers "F.Cu" "F.Mask" "F.Paste")
			(net "PD_ZQ")
		)
		(pad "L9" smd circle
			(at 3.199892 1.999996 270)
			(size 0.3556 0.3556)
			(layers "F.Cu" "F.Mask" "F.Paste")
			(net "Net_3")
		)
		(pad "M1" smd circle
			(at -3.199892 2.800096 270)
			(size 0.3556 0.3556)
			(layers "F.Cu" "F.Mask" "F.Paste")
			(net "GND")
		)
		(pad "M2" smd circle
			(at -2.400046 2.800096 270)
			(size 0.3556 0.3556)
			(layers "F.Cu" "F.Mask" "F.Paste")
			(net "MEMBA_0")
		)
		(pad "M3" smd circle
			(at -1.599946 2.800096 270)
			(size 0.3556 0.3556)
			(layers "F.Cu" "F.Mask" "F.Paste")
			(net "MEMBA_2")
		)
		(pad "M7" smd circle
			(at 1.599946 2.800096 270)
			(size 0.3556 0.3556)
			(layers "F.Cu" "F.Mask" "F.Paste")
			(net "Net_2")
		)
		(pad "M8" smd circle
			(at 2.400046 2.800096 270)
			(size 0.3556 0.3556)
			(layers "F.Cu" "F.Mask" "F.Paste")
			(net "DDR_VREF")
		)
		(pad "M9" smd circle
			(at 3.199892 2.800096 270)
			(size 0.3556 0.3556)
			(layers "F.Cu" "F.Mask" "F.Paste")
			(net "GND")
		)
		(pad "N1" smd circle
			(at -3.199892 3.599942 270)
			(size 0.3556 0.3556)
			(layers "F.Cu" "F.Mask" "F.Paste")
			(net "P1V53_STBY")
		)
		(pad "N2" smd circle
			(at -2.400046 3.599942 270)
			(size 0.3556 0.3556)
			(layers "F.Cu" "F.Mask" "F.Paste")
			(net "MEMA_3")
		)
		(pad "N3" smd circle
			(at -1.599946 3.599942 270)
			(size 0.3556 0.3556)
			(layers "F.Cu" "F.Mask" "F.Paste")
			(net "MEMA_0")
		)
		(pad "N7" smd circle
			(at 1.599946 3.599942 270)
			(size 0.3556 0.3556)
			(layers "F.Cu" "F.Mask" "F.Paste")
			(net "MEMA_12")
		)
		(pad "N8" smd circle
			(at 2.400046 3.599942 270)
			(size 0.3556 0.3556)
			(layers "F.Cu" "F.Mask" "F.Paste")
			(net "MEMBA_1")
		)
		(pad "N9" smd circle
			(at 3.199892 3.599942 270)
			(size 0.3556 0.3556)
			(layers "F.Cu" "F.Mask" "F.Paste")
			(net "P1V53_STBY")
		)
		(pad "P1" smd circle
			(at -3.199892 4.400042 270)
			(size 0.3556 0.3556)
			(layers "F.Cu" "F.Mask" "F.Paste")
			(net "GND")
		)
		(pad "P2" smd circle
			(at -2.400046 4.400042 270)
			(size 0.3556 0.3556)
			(layers "F.Cu" "F.Mask" "F.Paste")
			(net "MEMA_5")
		)
		(pad "P3" smd circle
			(at -1.599946 4.400042 270)
			(size 0.3556 0.3556)
			(layers "F.Cu" "F.Mask" "F.Paste")
			(net "MEMA_2")
		)
		(pad "P7" smd circle
			(at 1.599946 4.400042 270)
			(size 0.3556 0.3556)
			(layers "F.Cu" "F.Mask" "F.Paste")
			(net "MEMA_1")
		)
		(pad "P8" smd circle
			(at 2.400046 4.400042 270)
			(size 0.3556 0.3556)
			(layers "F.Cu" "F.Mask" "F.Paste")
			(net "MEMA_4")
		)
		(pad "P9" smd circle
			(at 3.199892 4.400042 270)
			(size 0.3556 0.3556)
			(layers "F.Cu" "F.Mask" "F.Paste")
			(net "GND")
		)
		(pad "R1" smd circle
			(at -3.199892 5.199888 270)
			(size 0.3556 0.3556)
			(layers "F.Cu" "F.Mask" "F.Paste")
			(net "P1V53_STBY")
		)
		(pad "R2" smd circle
			(at -2.400046 5.199888 270)
			(size 0.3556 0.3556)
			(layers "F.Cu" "F.Mask" "F.Paste")
			(net "MEMA_7")
		)
		(pad "R3" smd circle
			(at -1.599946 5.199888 270)
			(size 0.3556 0.3556)
			(layers "F.Cu" "F.Mask" "F.Paste")
			(net "MEMA_9")
		)
		(pad "R7" smd circle
			(at 1.599946 5.199888 270)
			(size 0.3556 0.3556)
			(layers "F.Cu" "F.Mask" "F.Paste")
			(net "MEMA_11")
		)
		(pad "R8" smd circle
			(at 2.400046 5.199888 270)
			(size 0.3556 0.3556)
			(layers "F.Cu" "F.Mask" "F.Paste")
			(net "MEMA_6")
		)
		(pad "R9" smd circle
			(at 3.199892 5.199888 270)
			(size 0.3556 0.3556)
			(layers "F.Cu" "F.Mask" "F.Paste")
			(net "P1V53_STBY")
		)
		(pad "T1" smd circle
			(at -3.199892 5.999988 270)
			(size 0.3556 0.3556)
			(layers "F.Cu" "F.Mask" "F.Paste")
			(net "GND")
		)
		(pad "T2" smd circle
			(at -2.400046 5.999988 270)
			(size 0.3556 0.3556)
			(layers "F.Cu" "F.Mask" "F.Paste")
			(net "BMC_DDR3_RST_N")
		)
		(pad "T3" smd circle
			(at -1.599946 5.999988 270)
			(size 0.3556 0.3556)
			(layers "F.Cu" "F.Mask" "F.Paste")
			(net "MEMA_13")
		)
		(pad "T7" smd circle
			(at 1.599946 5.999988 270)
			(size 0.3556 0.3556)
			(layers "F.Cu" "F.Mask" "F.Paste")
			(net "MEMA_14")
		)
		(pad "T8" smd circle
			(at 2.400046 5.999988 270)
			(size 0.3556 0.3556)
			(layers "F.Cu" "F.Mask" "F.Paste")
			(net "MEMA_8")
		)
		(pad "T9" smd circle
			(at 3.199892 5.999988 270)
			(size 0.3556 0.3556)
			(layers "F.Cu" "F.Mask" "F.Paste")
			(net "GND")
		)
	)
)
